(kicad_pcb
	(version 20241229)
	(generator "pcbnew")
	(generator_version "9.0")
	(general
		(thickness 1.61)
		(legacy_teardrops no)
	)
	(paper "A3")
	(title_block
		(title "RDIMM DDR5 Tester")
		(date "2026-05-21")
		(rev "2.2.0")
		(company "Antmicro")
		(comment 9 "footprints 362-366 of 796")
	)
	(layers
		(0 "F.Cu" signal)
		(4 "In1.Cu" power)
		(6 "In2.Cu" mixed)
		(8 "In3.Cu" power)
		(10 "In4.Cu" mixed)
		(12 "In5.Cu" power)
		(14 "In6.Cu" mixed)
		(16 "In7.Cu" power)
		(18 "In8.Cu" power)
		(20 "In9.Cu" mixed)
		(22 "In10.Cu" power)
		(2 "B.Cu" signal)
		(9 "F.Adhes" user "F.Adhesive")
		(11 "B.Adhes" user "B.Adhesive")
		(13 "F.Paste" user)
		(15 "B.Paste" user)
		(5 "F.SilkS" user "F.Silkscreen")
		(7 "B.SilkS" user "B.Silkscreen")
		(1 "F.Mask" user)
		(3 "B.Mask" user)
		(17 "Dwgs.User" user "User.Drawings")
		(19 "Cmts.User" user "User.Comments")
		(21 "Eco1.User" user "User.Eco1")
		(23 "Eco2.User" user "User.Eco2")
		(25 "Edge.Cuts" user)
		(27 "Margin" user)
		(31 "F.CrtYd" user "F.Courtyard")
		(29 "B.CrtYd" user "B.Courtyard")
		(35 "F.Fab" user)
		(33 "B.Fab" user)
	)
	(footprint "antmicro-footprints:C_0603_1608Metric"
		(layer "F.Cu")
		(at 250.293 156.521 -90)
		(descr "Capacitor SMD 0603")
		(tags "capacitor 0603")
		(property "Reference" "C190"
			(at 1.329 -0.557 90)
			(layer "F.SilkS")
			(effects
				(font
					(size 0.7 0.7)
					(thickness 0.15)
				)
				(justify right bottom)
			)
		)
		(property "Value" "C_22u_0603"
			(at -1.42757 1.770288 90)
			(layer "F.Fab")
			(effects
				(font
					(size 0.7 0.7)
					(thickness 0.15)
				)
				(justify right bottom)
			)
		)
		(property "Datasheet" "https://www.murata.com/products/productdetail?partno=GRM188R60J226MEA0%23"
			(at 0 0 270)
			(layer "F.Fab")
			(hide yes)
			(effects
				(font
					(size 1.27 1.27)
					(thickness 0.15)
				)
			)
		)
		(property "Manufacturer" "Murata"
			(at 0 0 270)
			(unlocked yes)
			(layer "F.Fab")
			(hide yes)
			(effects
				(font
					(size 1 1)
					(thickness 0.15)
				)
			)
		)
		(property "MPN" "GRM188R60J226MEA0D"
			(at 0 0 270)
			(unlocked yes)
			(layer "F.Fab")
			(hide yes)
			(effects
				(font
					(size 1 1)
					(thickness 0.15)
				)
			)
		)
		(property "Val" "22u"
			(at 0 0 270)
			(unlocked yes)
			(layer "F.Fab")
			(hide yes)
			(effects
				(font
					(size 1 1)
					(thickness 0.15)
				)
			)
		)
		(property "License" "Apache-2.0"
			(at 0 0 270)
			(unlocked yes)
			(layer "F.Fab")
			(hide yes)
			(effects
				(font
					(size 1 1)
					(thickness 0.15)
				)
			)
		)
		(property "Author" "Antmicro"
			(at 0 0 270)
			(unlocked yes)
			(layer "F.Fab")
			(hide yes)
			(effects
				(font
					(size 1 1)
					(thickness 0.15)
				)
			)
		)
		(property "Voltage" ""
			(at 0 0 270)
			(unlocked yes)
			(layer "F.Fab")
			(hide yes)
			(effects
				(font
					(size 1 1)
					(thickness 0.15)
				)
			)
		)
		(property "Dielectric" ""
			(at 0 0 270)
			(unlocked yes)
			(layer "F.Fab")
			(hide yes)
			(effects
				(font
					(size 1 1)
					(thickness 0.15)
				)
			)
		)
		(sheetname "/Supply/DC-DC IO/")
		(sheetfile "dc-dc-io.kicad_sch")
		(attr smd)
		(fp_line
			(start -0.15 0.4)
			(end 0.15 0.4)
			(stroke
				(width 0.15)
				(type solid)
			)
			(layer "F.SilkS")
		)
		(fp_line
			(start -0.15 -0.4)
			(end 0.15 -0.4)
			(stroke
				(width 0.15)
				(type solid)
			)
			(layer "F.SilkS")
		)
		(fp_rect
			(start -1.25 -0.65)
			(end 1.25 0.65)
			(stroke
				(width 0.05)
				(type solid)
			)
			(fill no)
			(layer "F.CrtYd")
		)
		(fp_rect
			(start -0.8 -0.4)
			(end 0.8 0.4)
			(stroke
				(width 0.15)
				(type solid)
			)
			(fill no)
			(layer "F.Fab")
		)
		(fp_text user "License: Apache-2.0"
			(at -1.682 5.895 270)
			(layer "F.Fab")
			(effects
				(font
					(size 0.7 0.7)
					(thickness 0.15)
				)
				(justify left bottom)
			)
		)
		(fp_text user "Author: Antmicro"
			(at -1.682 4.894 270)
			(layer "F.Fab")
			(effects
				(font
					(size 0.7 0.7)
					(thickness 0.15)
				)
				(justify left bottom)
			)
		)
		(fp_text user "${REFERENCE}"
			(at -1.682 3.895 270)
			(layer "F.Fab")
			(effects
				(font
					(size 0.7 0.7)
					(thickness 0.15)
				)
				(justify left bottom)
			)
		)
		(pad "1" smd roundrect
			(at -0.7 0 270)
			(size 0.8 1)
			(layers "F.Cu" "F.Mask" "F.Paste")
			(roundrect_rratio 0.2)
			(net 1 "GND")
			(pintype "passive")
		)
		(pad "2" smd roundrect
			(at 0.7 0 270)
			(size 0.8 1)
			(layers "F.Cu" "F.Mask" "F.Paste")
			(roundrect_rratio 0.2)
			(net 45 "/Supply/DC-DC IO/3V3_local")
			(pintype "passive")
		)
	)
	(footprint "antmicro-footprints:R_0402_1005Metric"
		(layer "F.Cu")
		(at 260.55 169.3945 90)
		(descr "Resistor SMD 0402")
		(tags "resistor SMD 0402")
		(property "Reference" "R163"
			(at 2.1945 0.35 90)
			(layer "F.SilkS")
			(effects
				(font
					(size 0.7 0.7)
					(thickness 0.15)
				)
				(justify left bottom)
			)
		)
		(property "Value" "R_0R_0402"
			(at -1.011843 1.772047 90)
			(layer "F.Fab")
			(effects
				(font
					(size 0.7 0.7)
					(thickness 0.15)
				)
				(justify left bottom)
			)
		)
		(property "Datasheet" "https://industrial.panasonic.com/cdbs/www-data/pdf/RDA0000/AOA0000C301.pdf"
			(at 0 0 90)
			(layer "F.Fab")
			(hide yes)
			(effects
				(font
					(size 1.27 1.27)
					(thickness 0.15)
				)
			)
		)
		(property "Manufacturer" "Panasonic"
			(at 0 0 90)
			(unlocked yes)
			(layer "F.Fab")
			(hide yes)
			(effects
				(font
					(size 1 1)
					(thickness 0.15)
				)
			)
		)
		(property "MPN" "ERJ2GE0R00X"
			(at 0 0 90)
			(unlocked yes)
			(layer "F.Fab")
			(hide yes)
			(effects
				(font
					(size 1 1)
					(thickness 0.15)
				)
			)
		)
		(property "Val" "0R"
			(at 0 0 90)
			(unlocked yes)
			(layer "F.Fab")
			(hide yes)
			(effects
				(font
					(size 1 1)
					(thickness 0.15)
				)
			)
		)
		(property "License" "Apache-2.0"
			(at 0 0 90)
			(unlocked yes)
			(layer "F.Fab")
			(hide yes)
			(effects
				(font
					(size 1 1)
					(thickness 0.15)
				)
			)
		)
		(property "Author" "Antmicro"
			(at 0 0 90)
			(unlocked yes)
			(layer "F.Fab")
			(hide yes)
			(effects
				(font
					(size 1 1)
					(thickness 0.15)
				)
			)
		)
		(property "Tolerance" "~"
			(at 0 0 90)
			(unlocked yes)
			(layer "F.Fab")
			(hide yes)
			(effects
				(font
					(size 1 1)
					(thickness 0.15)
				)
			)
		)
		(property "Current" "1A"
			(at 0 0 90)
			(unlocked yes)
			(layer "F.Fab")
			(hide yes)
			(effects
				(font
					(size 1 1)
					(thickness 0.15)
				)
			)
		)
		(sheetname "/Supply/DC-DC AUX, MGT/")
		(sheetfile "dc-dc-aux-mgt.kicad_sch")
		(attr smd)
		(fp_rect
			(start -0.925 -0.47)
			(end 0.925 0.47)
			(stroke
				(width 0.05)
				(type default)
			)
			(fill no)
			(layer "F.CrtYd")
		)
		(fp_rect
			(start -0.5 -0.25)
			(end 0.5 0.25)
			(stroke
				(width 0.15)
				(type solid)
			)
			(fill no)
			(layer "F.Fab")
		)
		(fp_text user "License: Apache-2.0"
			(at -0.95 5.169 90)
			(layer "F.Fab")
			(effects
				(font
					(size 0.7 0.7)
					(thickness 0.15)
				)
				(justify left bottom)
			)
		)
		(fp_text user "${REFERENCE}"
			(at -0.95 3.168 90)
			(layer "F.Fab")
			(effects
				(font
					(size 0.7 0.7)
					(thickness 0.15)
				)
				(justify left bottom)
			)
		)
		(fp_text user "Author: Antmicro"
			(at -0.95 4.169 90)
			(layer "F.Fab")
			(effects
				(font
					(size 0.7 0.7)
					(thickness 0.15)
				)
				(justify left bottom)
			)
		)
		(pad "1" smd roundrect
			(at -0.48 0 90)
			(size 0.59 0.64)
			(layers "F.Cu" "F.Mask" "F.Paste")
			(roundrect_rratio 0.25)
			(net 716 "/Supply/DC-DC AUX, MGT/FB3")
			(pintype "passive")
		)
		(pad "2" smd roundrect
			(at 0.48 0 90)
			(size 0.59 0.64)
			(layers "F.Cu" "F.Mask" "F.Paste")
			(roundrect_rratio 0.25)
			(net 47 "/Supply/DC-DC AUX, MGT/MGTAVCC_local")
			(pintype "passive")
		)
	)
	(footprint "antmicro-footprints:R_0402_1005Metric"
		(layer "F.Cu")
		(at 123.681 166.1125 90)
		(descr "Resistor SMD 0402")
		(tags "resistor SMD 0402")
		(property "Reference" "R229"
			(at 0.9125 3.969 90)
			(layer "F.SilkS")
			(effects
				(font
					(size 0.7 0.7)
					(thickness 0.15)
				)
				(justify left bottom)
			)
		)
		(property "Value" "R_64k9_0402"
			(at -1.011843 1.772047 90)
			(layer "F.Fab")
			(effects
				(font
					(size 0.7 0.7)
					(thickness 0.15)
				)
				(justify left bottom)
			)
		)
		(property "Datasheet" "https://www.bourns.com/docs/product-datasheets/cr.pdf"
			(at 0 0 90)
			(layer "F.Fab")
			(hide yes)
			(effects
				(font
					(size 1.27 1.27)
					(thickness 0.15)
				)
			)
		)
		(property "MPN" "CR0402-FX-6492GLF"
			(at 0 0 90)
			(unlocked yes)
			(layer "F.Fab")
			(hide yes)
			(effects
				(font
					(size 1 1)
					(thickness 0.15)
				)
			)
		)
		(property "Manufacturer" "Bourns"
			(at 0 0 90)
			(unlocked yes)
			(layer "F.Fab")
			(hide yes)
			(effects
				(font
					(size 1 1)
					(thickness 0.15)
				)
			)
		)
		(property "License" "Apache-2.0"
			(at 0 0 90)
			(unlocked yes)
			(layer "F.Fab")
			(hide yes)
			(effects
				(font
					(size 1 1)
					(thickness 0.15)
				)
			)
		)
		(property "Author" "Antmicro"
			(at 0 0 90)
			(unlocked yes)
			(layer "F.Fab")
			(hide yes)
			(effects
				(font
					(size 1 1)
					(thickness 0.15)
				)
			)
		)
		(property "Val" "64k9"
			(at 0 0 90)
			(unlocked yes)
			(layer "F.Fab")
			(hide yes)
			(effects
				(font
					(size 1 1)
					(thickness 0.15)
				)
			)
		)
		(property "Tolerance" "1%"
			(at 0 0 90)
			(unlocked yes)
			(layer "F.Fab")
			(hide yes)
			(effects
				(font
					(size 1 1)
					(thickness 0.15)
				)
			)
		)
		(sheetname "/HDMI + SD Card/")
		(sheetfile "hdmi-sd-card.kicad_sch")
		(attr smd exclude_from_bom dnp)
		(fp_rect
			(start -0.925 -0.47)
			(end 0.925 0.47)
			(stroke
				(width 0.05)
				(type default)
			)
			(fill no)
			(layer "F.CrtYd")
		)
		(fp_rect
			(start -0.5 -0.25)
			(end 0.5 0.25)
			(stroke
				(width 0.15)
				(type solid)
			)
			(fill no)
			(layer "F.Fab")
		)
		(fp_text user "${REFERENCE}"
			(at -0.95 3.168 90)
			(layer "F.Fab")
			(effects
				(font
					(size 0.7 0.7)
					(thickness 0.15)
				)
				(justify left bottom)
			)
		)
		(fp_text user "Author: Antmicro"
			(at -0.95 4.169 90)
			(layer "F.Fab")
			(effects
				(font
					(size 0.7 0.7)
					(thickness 0.15)
				)
				(justify left bottom)
			)
		)
		(fp_text user "License: Apache-2.0"
			(at -0.95 5.169 90)
			(layer "F.Fab")
			(effects
				(font
					(size 0.7 0.7)
					(thickness 0.15)
				)
				(justify left bottom)
			)
		)
		(pad "1" smd roundrect
			(at -0.48 0 90)
			(size 0.59 0.64)
			(layers "F.Cu" "F.Mask" "F.Paste")
			(roundrect_rratio 0.25)
			(net 739 "/HDMI + SD Card/TX_TERM_CTL")
			(pintype "passive")
		)
		(pad "2" smd roundrect
			(at 0.48 0 90)
			(size 0.59 0.64)
			(layers "F.Cu" "F.Mask" "F.Paste")
			(roundrect_rratio 0.25)
			(net 151 "+3V3")
			(pintype "passive")
		)
	)
	(footprint "antmicro-footprints:NetTie-2_SMD_Pad0.127mm"
		(layer "F.Cu")
		(at 256.72 165.62 180)
		(descr "Net tie, 2 pin, 0.127mm  SMD pads")
		(tags "net tie")
		(property "Reference" "NT11"
			(at -0.128 -1.345 0)
			(layer "F.SilkS")
			(hide yes)
			(effects
				(font
					(size 0.7 0.7)
					(thickness 0.15)
				)
				(justify right bottom)
			)
		)
		(property "Value" "Net-Tie_P0.127mm"
			(at 0 1.199 0)
			(layer "F.Fab")
			(effects
				(font
					(size 0.7 0.7)
					(thickness 0.15)
				)
				(justify right bottom)
			)
		)
		(property "MPN" ""
			(at 0 0 180)
			(unlocked yes)
			(layer "F.Fab")
			(hide yes)
			(effects
				(font
					(size 1 1)
					(thickness 0.15)
				)
			)
		)
		(property "Manufacturer" ""
			(at 0 0 180)
			(unlocked yes)
			(layer "F.Fab")
			(hide yes)
			(effects
				(font
					(size 1 1)
					(thickness 0.15)
				)
			)
		)
		(property "Author" "Antmicro"
			(at 0 0 180)
			(unlocked yes)
			(layer "F.Fab")
			(hide yes)
			(effects
				(font
					(size 1 1)
					(thickness 0.15)
				)
			)
		)
		(property "License" "Apache-2.0"
			(at 0 0 180)
			(unlocked yes)
			(layer "F.Fab")
			(hide yes)
			(effects
				(font
					(size 1 1)
					(thickness 0.15)
				)
			)
		)
		(property ki_fp_filters "Net*Tie*")
		(sheetname "/Supply/DC-DC AUX, MGT/")
		(sheetfile "dc-dc-aux-mgt.kicad_sch")
		(attr through_hole exclude_from_pos_files exclude_from_bom)
		(net_tie_pad_groups "1, 2")
		(fp_poly
			(pts
				(xy -0.0635 -0.0635) (xy 0.0625 -0.0635) (xy 0.0625 0.0635) (xy -0.0635 0.0635)
			)
			(stroke
				(width 0)
				(type solid)
			)
			(fill yes)
			(layer "F.Cu")
		)
		(fp_poly
			(pts
				(xy 0.2 -0.16) (xy 0.29 -0.07) (xy 0.29 0.07) (xy 0.2 0.16) (xy -0.2 0.16) (xy -0.29 0.07) (xy -0.29 -0.06)
				(xy -0.19 -0.16)
			)
			(stroke
				(width 0.05)
				(type solid)
			)
			(fill no)
			(layer "F.CrtYd")
		)
		(fp_text user "License: Apache-2.0"
			(at -0.128 5.6 180)
			(layer "F.Fab")
			(effects
				(font
					(size 0.7 0.7)
					(thickness 0.15)
				)
				(justify left bottom)
			)
		)
		(fp_text user "${REFERENCE}"
			(at -0.128 3.2 180)
			(layer "F.Fab")
			(effects
				(font
					(size 0.7 0.7)
					(thickness 0.15)
				)
				(justify left bottom)
			)
		)
		(fp_text user "Author: Antmicro"
			(at -0.128 4.4 180)
			(layer "F.Fab")
			(effects
				(font
					(size 0.7 0.7)
					(thickness 0.15)
				)
				(justify left bottom)
			)
		)
		(pad "1" smd roundrect
			(at -0.127 0)
			(size 0.127 0.127)
			(layers "F.Cu")
			(roundrect_rratio 0.5)
			(chamfer_ratio 0)
			(chamfer top_left bottom_left)
			(net 691 "/Supply/DC-DC AUX, MGT/MGTAVCC_SEN_-")
			(pinfunction "1")
			(pintype "passive")
		)
		(pad "2" smd roundrect
			(at 0.126 0 180)
			(size 0.127 0.127)
			(layers "F.Cu")
			(roundrect_rratio 0.5)
			(chamfer_ratio 0)
			(chamfer top_left bottom_left)
			(net 820 "+0V9_MGTAVCC")
			(pinfunction "2")
			(pintype "passive")
		)
	)
	(footprint "antmicro-footprints:TP_1206_SMD_RCW-0C"
		(layer "F.Cu")
		(at 262.414 161.85 90)
		(property "Reference" "TP21"
			(at -2.29 -1.4 90)
			(layer "F.SilkS")
			(hide yes)
			(effects
				(font
					(size 0.7 0.7)
					(thickness 0.15)
				)
				(justify left bottom)
			)
		)
		(property "Value" "TP_1206_SMD_RCW-0C"
			(at -4.68 2.25 90)
			(layer "F.Fab")
			(effects
				(font
					(size 0.7 0.7)
					(thickness 0.15)
				)
				(justify left bottom)
			)
		)
		(property "Datasheet" "https://www.te.com/commerce/DocumentDelivery/DDEController?Action=srchrtrv&DocNm=1773266&DocType=DS&DocLang=English"
			(at 0 0 90)
			(layer "F.Fab")
			(hide yes)
			(effects
				(font
					(size 1.27 1.27)
					(thickness 0.15)
				)
			)
		)
		(property "MPN" "RCW-0C"
			(at 0 0 90)
			(unlocked yes)
			(layer "F.Fab")
			(hide yes)
			(effects
				(font
					(size 1 1)
					(thickness 0.15)
				)
			)
		)
		(property "Manufacturer" "TE Connectivity"
			(at 0 0 90)
			(unlocked yes)
			(layer "F.Fab")
			(hide yes)
			(effects
				(font
					(size 1 1)
					(thickness 0.15)
				)
			)
		)
		(property "Author" "Antmicro"
			(at 0 0 90)
			(unlocked yes)
			(layer "F.Fab")
			(hide yes)
			(effects
				(font
					(size 1 1)
					(thickness 0.15)
				)
			)
		)
		(property "License" "Apache-2.0"
			(at 0 0 90)
			(unlocked yes)
			(layer "F.Fab")
			(hide yes)
			(effects
				(font
					(size 1 1)
					(thickness 0.15)
				)
			)
		)
		(sheetname "/Supply/")
		(sheetfile "supply.kicad_sch")
		(attr smd)
		(fp_line
			(start 1.78 -0.981)
			(end 1.281 -0.981)
			(stroke
				(width 0.15)
				(type solid)
			)
			(layer "F.SilkS")
		)
		(fp_line
			(start 1.78 -0.981)
			(end 1.78 -0.479)
			(stroke
				(width 0.15)
				(type solid)
			)
			(layer "F.SilkS")
		)
		(fp_line
			(start -1.779 -0.981)
			(end -1.279 -0.981)
			(stroke
				(width 0.15)
				(type solid)
			)
			(layer "F.SilkS")
		)
		(fp_line
			(start -1.779 -0.981)
			(end -1.779 -0.479)
			(stroke
				(width 0.15)
				(type solid)
			)
			(layer "F.SilkS")
		)
		(fp_line
			(start -1.779 0.482)
			(end -1.779 0.98)
			(stroke
				(width 0.15)
				(type solid)
			)
			(layer "F.SilkS")
		)
		(fp_line
			(start -1.779 0.98)
			(end -1.279 0.98)
			(stroke
				(width 0.15)
				(type solid)
			)
			(layer "F.SilkS")
		)
		(fp_line
			(start 1.78 0.982)
			(end 1.78 0.482)
			(stroke
				(width 0.15)
				(type solid)
			)
			(layer "F.SilkS")
		)
		(fp_line
			(start 1.78 0.982)
			(end 1.281 0.982)
			(stroke
				(width 0.15)
				(type solid)
			)
			(layer "F.SilkS")
		)
		(fp_rect
			(start -2.101 -1.314)
			(end 2.1 1.312)
			(stroke
				(width 0.05)
				(type solid)
			)
			(fill no)
			(layer "F.CrtYd")
		)
		(fp_rect
			(start -1.601 -0.814)
			(end 1.6 0.812)
			(stroke
				(width 0.15)
				(type solid)
			)
			(fill no)
			(layer "F.Fab")
		)
		(fp_text user "License: Apache-2.0"
			(at -4.68 5.45 90)
			(layer "F.Fab")
			(effects
				(font
					(size 0.7 0.7)
					(thickness 0.15)
				)
				(justify left bottom)
			)
		)
		(fp_text user "Author: Antmicro"
			(at -4.68 4.25 90)
			(layer "F.Fab")
			(effects
				(font
					(size 0.7 0.7)
					(thickness 0.15)
				)
				(justify left bottom)
			)
		)
		(fp_text user "${REFERENCE}"
			(at -4.68 6.65 90)
			(layer "F.Fab")
			(effects
				(font
					(size 0.7 0.7)
					(thickness 0.15)
				)
				(justify left bottom)
			)
		)
		(pad "1" smd rect
			(at 0 0 90)
			(size 3.4 1.8)
			(layers "F.Cu" "F.Mask" "F.Paste")
			(net 1 "GND")
			(pinfunction "1")
			(pintype "passive")
		)
	)
)
